# S9S_MB_2U (Grand Teton) — schematic netlist excerpt (pin names and nets, part order shuffled) for the footprints in the layout excerpt that follows; sources: Cadence DE-HDL packaged netlist, KiCad conversion of 03242023_DA0F0TMBIJ0_F0T_Motherboard_J_brd_V01_OCP.brd

H105  HOLE  EMPTY  pkg TH  page 311 : \1\ = GND

U59  74LVC2G07DW7  74LVC2G07DW-7 IC  pkg SOT363_0-65_2X1-25XC  page 162
  \1a\  = OCP_V3_2_PRSNT2_R_N
  GND  = GND
  \2a\  = OCP_V3_2_PRSNT3_R_N
  \2y\  = HP_LVC3_OCP_V3_2_PRSNT2_N_R
  VCC  = P3V3_AUX
  \1y\  = HP_LVC3_OCP_V3_2_PRSNT2_N_R

R237  Q_RES  1.5K 1% CHIP  pkg 0402LF  page 121 : A = H_CPU0_THERMTRIP_LVC1_R_N ; B = H_CPU0_THERMTRIP_VT_R_N

(kicad_pcb
	(version 20260206)
	(generator "pcbnew")
	(generator_version "10.0")
	(general
		(thickness 1.6)
		(legacy_teardrops no)
	)
	(paper "A4")
	(title_block
		(title "03242023_DA0F0TMBIJ0_F0T_Motherboard_J_brd_V01_OCP.brd")
		(comment 1 "Grand Teton / footprints 3153-3155 of 6105")
	)
	(layers
		(0 "F.Cu" signal "TOP")
		(4 "In1.Cu" signal "GND")
		(6 "In2.Cu" signal "IN1")
		(8 "In3.Cu" signal "GND1")
		(10 "In4.Cu" signal "IN2")
		(12 "In5.Cu" signal "GND2")
		(14 "In6.Cu" signal "IN3")
		(16 "In7.Cu" signal "GND3")
		(18 "In8.Cu" signal "VCC")
		(20 "In9.Cu" signal "VCC1")
		(22 "In10.Cu" signal "GND4")
		(24 "In11.Cu" signal "IN4")
		(26 "In12.Cu" signal "GND5")
		(28 "In13.Cu" signal "IN5")
		(30 "In14.Cu" signal "GND6")
		(32 "In15.Cu" signal "IN6")
		(34 "In16.Cu" signal "GND7")
		(2 "B.Cu" signal "BOTTOM")
		(9 "F.Adhes" user "F.Adhesive")
		(11 "B.Adhes" user "B.Adhesive")
		(13 "F.Paste" user "Package Geometry/Pastemask Top")
		(15 "B.Paste" user "Package Geometry/Pastemask Bottom")
		(5 "F.SilkS" user "Ref Des/Silkscreen Top")
		(7 "B.SilkS" user "Ref Des/Silkscreen Bottom")
		(1 "F.Mask" user "Board Geometry/Soldermask Top")
		(3 "B.Mask" user "Board Geometry/Soldermask Bottom")
		(17 "Dwgs.User" user "User.Drawings")
		(19 "Cmts.User" user "User.Comments")
		(21 "Eco1.User" user "User.Eco1")
		(23 "Eco2.User" user "User.Eco2")
		(25 "Edge.Cuts" user "Board Geometry/Outline")
		(27 "Margin" user)
		(31 "F.CrtYd" user "Package Geometry/Place Bound Top")
		(29 "B.CrtYd" user "Package Geometry/Place Bound Bottom")
		(35 "F.Fab" user "Ref Des/Assembly Top")
		(33 "B.Fab" user "Ref Des/Assembly Bottom")
	)
	(footprint ""
		(layer "F.Cu")
		(at 24.67356 -71.821548)
		(property "Reference" "U59"
			(at -1.4732 -1.768348 0)
			(unlocked yes)
			(layer "F.SilkS")
			(effects
				(font
					(size 0.7874 0.5842)
					(thickness 0.1524)
				)
				(justify left)
			)
		)
		(property "Value" ""
			(at 0 0 0)
			(layer "F.Fab")
			(effects
				(font
					(size 1.27 1.27)
				)
			)
		)
		(duplicate_pad_numbers_are_jumpers no)
		(fp_line
			(start -1.38176 -1.100074)
			(end -1.38176 1.100074)
			(stroke
				(width 0.1524)
				(type default)
			)
			(layer "F.SilkS")
		)
		(fp_line
			(start -1.38176 1.100074)
			(end 1.38176 1.100074)
			(stroke
				(width 0.1524)
				(type default)
			)
			(layer "F.SilkS")
		)
		(fp_line
			(start -0.592074 -1.100074)
			(end -1.38176 -1.100074)
			(stroke
				(width 0.1524)
				(type default)
			)
			(layer "F.SilkS")
		)
		(fp_line
			(start 0 -0.508)
			(end -0.592074 -1.100074)
			(stroke
				(width 0.1524)
				(type default)
			)
			(layer "F.SilkS")
		)
		(fp_line
			(start 0.592074 -1.100074)
			(end 0 -0.508)
			(stroke
				(width 0.1524)
				(type default)
			)
			(layer "F.SilkS")
		)
		(fp_line
			(start 1.38176 -1.100074)
			(end 0.592074 -1.100074)
			(stroke
				(width 0.1524)
				(type default)
			)
			(layer "F.SilkS")
		)
		(fp_line
			(start 1.38176 1.100074)
			(end 1.38176 -1.100074)
			(stroke
				(width 0.1524)
				(type default)
			)
			(layer "F.SilkS")
		)
		(fp_poly
			(pts
				(xy -1.60909 -0.649986) (xy -2.04978 -0.429768) (xy -2.04978 -0.870204)
			)
			(stroke
				(width 0)
				(type default)
			)
			(fill yes)
			(layer "F.SilkS")
		)
		(fp_line
			(start -0.674878 -1.100074)
			(end -0.674878 1.100074)
			(stroke
				(width 0.1)
				(type default)
			)
			(layer "F.Fab")
		)
		(fp_line
			(start -0.674878 1.100074)
			(end 0.674878 1.100074)
			(stroke
				(width 0.1)
				(type default)
			)
			(layer "F.Fab")
		)
		(fp_line
			(start 0.674878 -1.100074)
			(end -0.674878 -1.100074)
			(stroke
				(width 0.1)
				(type default)
			)
			(layer "F.Fab")
		)
		(fp_line
			(start 0.674878 1.100074)
			(end 0.674878 -1.100074)
			(stroke
				(width 0.1)
				(type default)
			)
			(layer "F.Fab")
		)
		(fp_poly
			(pts
				(xy -1.9431 -0.870204) (xy -1.50241 -0.649986) (xy -1.9431 -0.429768)
			)
			(stroke
				(width 0)
				(type default)
			)
			(fill yes)
			(layer "F.Fab")
		)
		(pad "1" smd rect
			(at -0.94996 -0.649986 270)
			(size 0.4318 0.6096)
			(layers "F.Cu" "F.Mask" "F.Paste")
			(net "OCP_V3_2_PRSNT2_R_N")
		)
		(pad "2" smd rect
			(at -0.94996 0 270)
			(size 0.4318 0.6096)
			(layers "F.Cu" "F.Mask" "F.Paste")
			(net "GND")
		)
		(pad "3" smd rect
			(at -0.94996 0.649986 270)
			(size 0.4318 0.6096)
			(layers "F.Cu" "F.Mask" "F.Paste")
			(net "OCP_V3_2_PRSNT3_R_N")
		)
		(pad "4" smd rect
			(at 0.94996 0.649986 270)
			(size 0.4318 0.6096)
			(layers "F.Cu" "F.Mask" "F.Paste")
			(net "HP_LVC3_OCP_V3_2_PRSNT2_N_R")
		)
		(pad "5" smd rect
			(at 0.94996 0 270)
			(size 0.4318 0.6096)
			(layers "F.Cu" "F.Mask" "F.Paste")
			(net "P3V3_AUX")
		)
		(pad "6" smd rect
			(at 0.94996 -0.649986 270)
			(size 0.4318 0.6096)
			(layers "F.Cu" "F.Mask" "F.Paste")
			(net "HP_LVC3_OCP_V3_2_PRSNT2_N_R")
		)
	)
	(footprint ""
		(layer "F.Cu")
		(at 380.899924 -22.29993)
		(property "Reference" "H105"
			(at -6.516624 -4.37896 0)
			(unlocked yes)
			(layer "F.SilkS")
			(effects
				(font
					(size 0.7874 0.5842)
					(thickness 0.1524)
				)
				(justify left)
			)
		)
		(property "Value" ""
			(at 0 0 0)
			(layer "F.Fab")
			(effects
				(font
					(size 1.27 1.27)
				)
			)
		)
		(duplicate_pad_numbers_are_jumpers no)
		(pad "1" thru_hole circle
			(at 0 0)
			(size 10.0076 10.0076)
			(drill 5.6134)
			(layers "*.Cu" "*.Mask")
			(remove_unused_layers no)
			(net "GND")
			(clearance -1.9431)
		)
	)
	(footprint ""
		(layer "F.Cu")
		(at 121.59488 -92.674948 90)
		(property "Reference" "R237"
			(at 0 0 90)
			(layer "F.SilkS")
			(hide yes)
			(effects
				(font
					(size 1.27 1.27)
				)
			)
		)
		(property "Value" ""
			(at 0 0 90)
			(layer "F.Fab")
			(effects
				(font
					(size 1.27 1.27)
				)
			)
		)
		(duplicate_pad_numbers_are_jumpers no)
		(fp_line
			(start 0.7874 -0.4064)
			(end 0.7874 0.4064)
			(stroke
				(width 0.1524)
				(type default)
			)
			(layer "F.SilkS")
		)
		(fp_line
			(start -0.7874 -0.4064)
			(end 0.7874 -0.4064)
			(stroke
				(width 0.1524)
				(type default)
			)
			(layer "F.SilkS")
		)
		(fp_line
			(start 0.7874 0.4064)
			(end -0.7874 0.4064)
			(stroke
				(width 0.1524)
				(type default)
			)
			(layer "F.SilkS")
		)
		(fp_line
			(start -0.7874 0.4064)
			(end -0.7874 -0.4064)
			(stroke
				(width 0.1524)
				(type default)
			)
			(layer "F.SilkS")
		)
		(fp_line
			(start -0.12065 -0.305054)
			(end -0.12065 -0.2794)
			(stroke
				(width 0.1)
				(type default)
			)
			(layer "F.Fab")
		)
		(fp_line
			(start -0.67945 -0.305054)
			(end -0.12065 -0.305054)
			(stroke
				(width 0.1)
				(type default)
			)
			(layer "F.Fab")
		)
		(fp_line
			(start 0.67945 -0.3048)
			(end 0.67945 0.3048)
			(stroke
				(width 0.1)
				(type default)
			)
			(layer "F.Fab")
		)
		(fp_line
			(start 0.12065 -0.3048)
			(end 0.67945 -0.3048)
			(stroke
				(width 0.1)
				(type default)
			)
			(layer "F.Fab")
		)
		(fp_line
			(start 0.12065 -0.2794)
			(end 0.12065 -0.3048)
			(stroke
				(width 0.1)
				(type default)
			)
			(layer "F.Fab")
		)
		(fp_line
			(start -0.12065 -0.2794)
			(end 0.12065 -0.2794)
			(stroke
				(width 0.1)
				(type default)
			)
			(layer "F.Fab")
		)
		(fp_line
			(start 0.120396 0.2794)
			(end -0.12065 0.2794)
			(stroke
				(width 0.1)
				(type default)
			)
			(layer "F.Fab")
		)
		(fp_line
			(start -0.12065 0.2794)
			(end -0.12065 0.3048)
			(stroke
				(width 0.1)
				(type default)
			)
			(layer "F.Fab")
		)
		(fp_line
			(start 0.67945 0.3048)
			(end 0.120396 0.3048)
			(stroke
				(width 0.1)
				(type default)
			)
			(layer "F.Fab")
		)
		(fp_line
			(start 0.120396 0.3048)
			(end 0.120396 0.2794)
			(stroke
				(width 0.1)
				(type default)
			)
			(layer "F.Fab")
		)
		(fp_line
			(start -0.12065 0.3048)
			(end -0.67945 0.3048)
			(stroke
				(width 0.1)
				(type default)
			)
			(layer "F.Fab")
		)
		(fp_line
			(start -0.67945 0.3048)
			(end -0.67945 -0.305054)
			(stroke
				(width 0.1)
				(type default)
			)
			(layer "F.Fab")
		)
		(pad "1" smd circle
			(at -0.40005 0 90)
			(size 0 0)
			(layers "F.Cu" "F.Mask" "F.Paste")
			(net "H_CPU0_THERMTRIP_LVC1_R_N")
		)
		(pad "2" smd circle
			(at 0.40005 0 90)
			(size 0 0)
			(layers "F.Cu" "F.Mask" "F.Paste")
			(net "H_CPU0_THERMTRIP_VT_R_N")
		)
	)
)
